FILE_TYPE = MULTI_PHYS_TABLE;

PART 'SCONN11_9192031111LF'

{========================================================================================}
:VALUE                   | PART_TYPE | MATERIAL | PART_NUMBER    = STANDARD        | LIFECYCLE      | PART_NUMBER   | JEDEC_TYPE                 | DESCRIPTION                            | MANUFTR | MANUF_PN        | RD_CMPLS_LVL | CMPLS_LVL | CLASS | DIP_SMD | FROM_PJ  | DATA                    | FP_ECN | EE_CHECK_LIST | CREATOR | CREATEDAY  | PSL | STATUS | ESD_CDM | ESD_HBM | ESD_MM | MSD  | PIN_LENGTH_LONG_PIN | PIN_LENGTH_SHORT_PIN ;
{========================================================================================}
 'SCONN11_91920-31111LF' | 'SMLF'    | 'IO'     | 'DFHS11FS009'(!) = ''               | ''               | 'DFHS11FS009' |'CON_F11S2H2S_P1W4-22_LDH'| 'CONN SMD HOUSING 11P 2R FS(P1,H3.28)' | 'BER'   | '91920-31111LF' | 'EP(V1)'     | 'EP(V1)'  | 'IO'  | ''      | 'S9N-CY' | 'BER_91920-31111LF.pdf' | ''     | ''            | ''      | '20181102' | ''  | ''     | 'NA'    | 'NA'    | 'NA'   | 'NA' | '0 MILS'            | '0 MILS'            
 'SCONN11_91920-31111LF' | 'SMLF'    | 'EMPTY'  | 'DFHS11FS009'(!) = ''               | ''               | 'DFHS11FS009' |'CON_F11S2H2S_P1W4-22_LDH'| 'CONN SMD HOUSING 11P 2R FS(P1,H3.28)' | 'BER'   | '91920-31111LF' | 'EP(V1)'     | 'EP(V1)'  | 'IO'  | ''      | 'S9N-CY' | 'BER_91920-31111LF.pdf' | ''     | ''            | ''      | '20181102' | ''  | ''     | 'NA'    | 'NA'    | 'NA'   | 'NA' | '0 MILS'            | '0 MILS'            

END_PART

END.

